(kicad_pcb
	(version 20260206)
	(generator "pcbnew")
	(generator_version "10.0")
	(general
		(thickness 1.6)
		(legacy_teardrops no)
	)
	(paper "A4")
	(title_block
		(title "04192023_DAF0TMB3IC0_F0TG_MB_C_brd_V02_OCP.brd")
		(comment 1 "Grand Teton / footprints 6332-6339 of 8354")
	)
	(layers
		(0 "F.Cu" signal "TOP")
		(4 "In1.Cu" signal "GND")
		(6 "In2.Cu" signal "IN1")
		(8 "In3.Cu" signal "GND1")
		(10 "In4.Cu" signal "IN2")
		(12 "In5.Cu" signal "GND2")
		(14 "In6.Cu" signal "IN3")
		(16 "In7.Cu" signal "GND3")
		(18 "In8.Cu" signal "VCC")
		(20 "In9.Cu" signal "VCC1")
		(22 "In10.Cu" signal "GND4")
		(24 "In11.Cu" signal "IN4")
		(26 "In12.Cu" signal "GND5")
		(28 "In13.Cu" signal "IN5")
		(30 "In14.Cu" signal "GND6")
		(32 "In15.Cu" signal "IN6")
		(34 "In16.Cu" signal "GND7")
		(2 "B.Cu" signal "BOTTOM")
		(9 "F.Adhes" user "F.Adhesive")
		(11 "B.Adhes" user "B.Adhesive")
		(13 "F.Paste" user "Package Geometry/Pastemask Top")
		(15 "B.Paste" user "Package Geometry/Pastemask Bottom")
		(5 "F.SilkS" user "Ref Des/Silkscreen Top")
		(7 "B.SilkS" user "Ref Des/Silkscreen Bottom")
		(1 "F.Mask" user "Board Geometry/Soldermask Top")
		(3 "B.Mask" user "Board Geometry/Soldermask Bottom")
		(17 "Dwgs.User" user "User.Drawings")
		(19 "Cmts.User" user "User.Comments")
		(21 "Eco1.User" user "User.Eco1")
		(23 "Eco2.User" user "User.Eco2")
		(25 "Edge.Cuts" user "Board Geometry/Outline")
		(27 "Margin" user)
		(31 "F.CrtYd" user "Package Geometry/Place Bound Top")
		(29 "B.CrtYd" user "Package Geometry/Place Bound Bottom")
		(35 "F.Fab" user "Ref Des/Assembly Top")
		(33 "B.Fab" user "Ref Des/Assembly Bottom")
	)
	(footprint ""
		(layer "B.Cu")
		(at 396.989554 -401.624546 180)
		(property "Reference" "R1053"
			(at 0 0 0)
			(layer "B.SilkS")
			(hide yes)
			(effects
				(font
					(size 1.27 1.27)
				)
				(justify mirror)
			)
		)
		(property "Value" ""
			(at 0 0 0)
			(layer "B.Fab")
			(effects
				(font
					(size 1.27 1.27)
				)
				(justify mirror)
			)
		)
		(duplicate_pad_numbers_are_jumpers no)
		(fp_line
			(start 1.2954 0.5842)
			(end 1.2954 -0.5842)
			(stroke
				(width 0.1524)
				(type default)
			)
			(layer "B.SilkS")
		)
		(fp_line
			(start 1.2954 -0.5842)
			(end -1.2954 -0.5842)
			(stroke
				(width 0.1524)
				(type default)
			)
			(layer "B.SilkS")
		)
		(fp_line
			(start -1.2954 0.5842)
			(end 1.2954 0.5842)
			(stroke
				(width 0.1524)
				(type default)
			)
			(layer "B.SilkS")
		)
		(fp_line
			(start -1.2954 -0.5842)
			(end -1.2954 0.5842)
			(stroke
				(width 0.1524)
				(type default)
			)
			(layer "B.SilkS")
		)
		(fp_line
			(start 1.1938 0.4064)
			(end 1.1938 -0.406654)
			(stroke
				(width 0.1)
				(type default)
			)
			(layer "B.Fab")
		)
		(fp_line
			(start 1.1938 -0.406654)
			(end 0.8636 -0.406654)
			(stroke
				(width 0.1)
				(type default)
			)
			(layer "B.Fab")
		)
		(fp_line
			(start 0.8636 0.4572)
			(end 0.8636 0.4318)
			(stroke
				(width 0.1)
				(type default)
			)
			(layer "B.Fab")
		)
		(fp_line
			(start 0.8636 0.4318)
			(end 0.8636 0.4064)
			(stroke
				(width 0.1)
				(type default)
			)
			(layer "B.Fab")
		)
		(fp_line
			(start 0.8636 0.4064)
			(end 1.1938 0.4064)
			(stroke
				(width 0.1)
				(type default)
			)
			(layer "B.Fab")
		)
		(fp_line
			(start 0.8636 -0.406654)
			(end 0.8636 -0.4572)
			(stroke
				(width 0.1)
				(type default)
			)
			(layer "B.Fab")
		)
		(fp_line
			(start 0.8636 -0.4572)
			(end -0.8636 -0.4572)
			(stroke
				(width 0.1)
				(type default)
			)
			(layer "B.Fab")
		)
		(fp_line
			(start -0.8636 0.4572)
			(end 0.8636 0.4572)
			(stroke
				(width 0.1)
				(type default)
			)
			(layer "B.Fab")
		)
		(fp_line
			(start -0.8636 0.4064)
			(end -0.8636 0.4572)
			(stroke
				(width 0.1)
				(type default)
			)
			(layer "B.Fab")
		)
		(fp_line
			(start -0.8636 -0.406654)
			(end -1.1938 -0.406654)
			(stroke
				(width 0.1)
				(type default)
			)
			(layer "B.Fab")
		)
		(fp_line
			(start -0.8636 -0.4572)
			(end -0.8636 -0.406654)
			(stroke
				(width 0.1)
				(type default)
			)
			(layer "B.Fab")
		)
		(fp_line
			(start -1.1938 0.4064)
			(end -0.8636 0.4064)
			(stroke
				(width 0.1)
				(type default)
			)
			(layer "B.Fab")
		)
		(fp_line
			(start -1.1938 -0.406654)
			(end -1.1938 0.4064)
			(stroke
				(width 0.1)
				(type default)
			)
			(layer "B.Fab")
		)
		(pad "1" smd rect
			(at 0.7366 0 90)
			(size 0.7112 0.8128)
			(layers "B.Cu" "B.Mask" "B.Paste")
			(net "P0V9_CPU0_RT2_2A_2D")
		)
		(pad "2" smd rect
			(at -0.7366 0 90)
			(size 0.7112 0.8128)
			(layers "B.Cu" "B.Mask" "B.Paste")
			(net "P0V9_CPU0_RT2_2A")
		)
	)
	(footprint ""
		(layer "B.Cu")
		(at 110.48746 -35.088068 90)
		(property "Reference" "C6115"
			(at 0 0 90)
			(layer "B.SilkS")
			(hide yes)
			(effects
				(font
					(size 1.27 1.27)
				)
				(justify mirror)
			)
		)
		(property "Value" ""
			(at 0 0 90)
			(layer "B.Fab")
			(effects
				(font
					(size 1.27 1.27)
				)
				(justify mirror)
			)
		)
		(duplicate_pad_numbers_are_jumpers no)
		(fp_line
			(start 0.7874 -0.4064)
			(end -0.7874 -0.4064)
			(stroke
				(width 0.1524)
				(type default)
			)
			(layer "B.SilkS")
		)
		(fp_line
			(start -0.7874 -0.4064)
			(end -0.7874 0.4064)
			(stroke
				(width 0.1524)
				(type default)
			)
			(layer "B.SilkS")
		)
		(fp_line
			(start 0.7874 0.4064)
			(end 0.7874 -0.4064)
			(stroke
				(width 0.1524)
				(type default)
			)
			(layer "B.SilkS")
		)
		(fp_line
			(start -0.7874 0.4064)
			(end 0.7874 0.4064)
			(stroke
				(width 0.1524)
				(type default)
			)
			(layer "B.SilkS")
		)
		(fp_line
			(start 0.67945 -0.305054)
			(end 0.12065 -0.305054)
			(stroke
				(width 0.1)
				(type default)
			)
			(layer "B.Fab")
		)
		(fp_line
			(start 0.12065 -0.305054)
			(end 0.12065 -0.2794)
			(stroke
				(width 0.1)
				(type default)
			)
			(layer "B.Fab")
		)
		(fp_line
			(start -0.12065 -0.3048)
			(end -0.67945 -0.3048)
			(stroke
				(width 0.1)
				(type default)
			)
			(layer "B.Fab")
		)
		(fp_line
			(start -0.67945 -0.3048)
			(end -0.67945 0.3048)
			(stroke
				(width 0.1)
				(type default)
			)
			(layer "B.Fab")
		)
		(fp_line
			(start 0.12065 -0.2794)
			(end -0.12065 -0.2794)
			(stroke
				(width 0.1)
				(type default)
			)
			(layer "B.Fab")
		)
		(fp_line
			(start -0.12065 -0.2794)
			(end -0.12065 -0.3048)
			(stroke
				(width 0.1)
				(type default)
			)
			(layer "B.Fab")
		)
		(fp_line
			(start 0.12065 0.2794)
			(end 0.12065 0.3048)
			(stroke
				(width 0.1)
				(type default)
			)
			(layer "B.Fab")
		)
		(fp_line
			(start -0.120396 0.2794)
			(end 0.12065 0.2794)
			(stroke
				(width 0.1)
				(type default)
			)
			(layer "B.Fab")
		)
		(fp_line
			(start 0.67945 0.3048)
			(end 0.67945 -0.305054)
			(stroke
				(width 0.1)
				(type default)
			)
			(layer "B.Fab")
		)
		(fp_line
			(start 0.12065 0.3048)
			(end 0.67945 0.3048)
			(stroke
				(width 0.1)
				(type default)
			)
			(layer "B.Fab")
		)
		(fp_line
			(start -0.120396 0.3048)
			(end -0.120396 0.2794)
			(stroke
				(width 0.1)
				(type default)
			)
			(layer "B.Fab")
		)
		(fp_line
			(start -0.67945 0.3048)
			(end -0.120396 0.3048)
			(stroke
				(width 0.1)
				(type default)
			)
			(layer "B.Fab")
		)
		(pad "1" smd circle
			(at 0.40005 0 270)
			(size 0 0)
			(layers "B.Cu" "B.Mask" "B.Paste")
			(net "P1V2_CPU0_USB2_DVDD12")
		)
		(pad "2" smd circle
			(at -0.40005 0 270)
			(size 0 0)
			(layers "B.Cu" "B.Mask" "B.Paste")
			(net "GND")
		)
	)
	(footprint ""
		(layer "B.Cu")
		(at 400.727672 -396.991078 90)
		(property "Reference" "C784"
			(at 0 0 90)
			(layer "B.SilkS")
			(hide yes)
			(effects
				(font
					(size 1.27 1.27)
				)
				(justify mirror)
			)
		)
		(property "Value" ""
			(at 0 0 90)
			(layer "B.Fab")
			(effects
				(font
					(size 1.27 1.27)
				)
				(justify mirror)
			)
		)
		(duplicate_pad_numbers_are_jumpers no)
		(fp_line
			(start 0.299974 -0.150114)
			(end -0.299974 -0.150114)
			(stroke
				(width 0.1)
				(type default)
			)
			(layer "B.Fab")
		)
		(fp_line
			(start -0.299974 -0.150114)
			(end -0.299974 0.150114)
			(stroke
				(width 0.1)
				(type default)
			)
			(layer "B.Fab")
		)
		(fp_line
			(start 0.299974 0.150114)
			(end 0.299974 -0.150114)
			(stroke
				(width 0.1)
				(type default)
			)
			(layer "B.Fab")
		)
		(fp_line
			(start -0.299974 0.150114)
			(end 0.299974 0.150114)
			(stroke
				(width 0.1)
				(type default)
			)
			(layer "B.Fab")
		)
		(pad "1" smd rect
			(at 0.2667 0 270)
			(size 0.3048 0.381)
			(layers "B.Cu" "B.Mask" "B.Paste")
			(net "P0V9_CPU0_RT2_2A")
		)
		(pad "2" smd rect
			(at -0.2667 0 270)
			(size 0.3048 0.381)
			(layers "B.Cu" "B.Mask" "B.Paste")
			(net "GND")
		)
	)
	(footprint ""
		(layer "B.Cu")
		(at 346.92082 -326.820276 -90)
		(property "Reference" "PC141_5"
			(at 0 0 90)
			(layer "B.SilkS")
			(hide yes)
			(effects
				(font
					(size 1.27 1.27)
				)
				(justify mirror)
			)
		)
		(property "Value" ""
			(at 0 0 90)
			(layer "B.Fab")
			(effects
				(font
					(size 1.27 1.27)
				)
				(justify mirror)
			)
		)
		(duplicate_pad_numbers_are_jumpers no)
		(fp_line
			(start -1.524 0.762)
			(end 1.524 0.762)
			(stroke
				(width 0.1524)
				(type default)
			)
			(layer "B.SilkS")
		)
		(fp_line
			(start 1.524 0.762)
			(end 1.524 -0.762)
			(stroke
				(width 0.1524)
				(type default)
			)
			(layer "B.SilkS")
		)
		(fp_line
			(start -1.524 -0.762)
			(end -1.524 0.762)
			(stroke
				(width 0.1524)
				(type default)
			)
			(layer "B.SilkS")
		)
		(fp_line
			(start 1.524 -0.762)
			(end -1.524 -0.762)
			(stroke
				(width 0.1524)
				(type default)
			)
			(layer "B.SilkS")
		)
		(fp_line
			(start -1.1049 0.724916)
			(end -1.1049 -0.724916)
			(stroke
				(width 0.1)
				(type default)
			)
			(layer "B.Fab")
		)
		(fp_line
			(start 1.1049 0.724916)
			(end -1.1049 0.724916)
			(stroke
				(width 0.1)
				(type default)
			)
			(layer "B.Fab")
		)
		(fp_line
			(start -1.1049 -0.724916)
			(end 1.1049 -0.724916)
			(stroke
				(width 0.1)
				(type default)
			)
			(layer "B.Fab")
		)
		(fp_line
			(start 1.1049 -0.724916)
			(end 1.1049 0.724916)
			(stroke
				(width 0.1)
				(type default)
			)
			(layer "B.Fab")
		)
		(pad "1" smd rect
			(at 0.889 0 270)
			(size 1.016 1.27)
			(layers "B.Cu" "B.Mask" "B.Paste")
			(net "PVDDCR_CPU1_P0")
		)
		(pad "2" smd rect
			(at -0.889 0 270)
			(size 1.016 1.27)
			(layers "B.Cu" "B.Mask" "B.Paste")
			(net "GND")
		)
	)
	(footprint ""
		(layer "B.Cu")
		(at 304.578258 -395.148562 90)
		(property "Reference" "C562"
			(at 0 0 90)
			(layer "B.SilkS")
			(hide yes)
			(effects
				(font
					(size 1.27 1.27)
				)
				(justify mirror)
			)
		)
		(property "Value" ""
			(at 0 0 90)
			(layer "B.Fab")
			(effects
				(font
					(size 1.27 1.27)
				)
				(justify mirror)
			)
		)
		(duplicate_pad_numbers_are_jumpers no)
		(fp_line
			(start 0.299974 -0.150114)
			(end -0.299974 -0.150114)
			(stroke
				(width 0.1)
				(type default)
			)
			(layer "B.Fab")
		)
		(fp_line
			(start -0.299974 -0.150114)
			(end -0.299974 0.150114)
			(stroke
				(width 0.1)
				(type default)
			)
			(layer "B.Fab")
		)
		(fp_line
			(start 0.299974 0.150114)
			(end 0.299974 -0.150114)
			(stroke
				(width 0.1)
				(type default)
			)
			(layer "B.Fab")
		)
		(fp_line
			(start -0.299974 0.150114)
			(end 0.299974 0.150114)
			(stroke
				(width 0.1)
				(type default)
			)
			(layer "B.Fab")
		)
		(pad "1" smd rect
			(at 0.2667 0 270)
			(size 0.3048 0.381)
			(layers "B.Cu" "B.Mask" "B.Paste")
			(net "P0V9_CPU0_RT0_2A")
		)
		(pad "2" smd rect
			(at -0.2667 0 270)
			(size 0.3048 0.381)
			(layers "B.Cu" "B.Mask" "B.Paste")
			(net "GND")
		)
	)
	(footprint ""
		(layer "B.Cu")
		(at 113.105946 -258.795266 180)
		(property "Reference" "C2276"
			(at 0 0 0)
			(layer "B.SilkS")
			(hide yes)
			(effects
				(font
					(size 1.27 1.27)
				)
				(justify mirror)
			)
		)
		(property "Value" ""
			(at 0 0 0)
			(layer "B.Fab")
			(effects
				(font
					(size 1.27 1.27)
				)
				(justify mirror)
			)
		)
		(duplicate_pad_numbers_are_jumpers no)
		(fp_line
			(start 0.7874 0.4064)
			(end 0.7874 -0.4064)
			(stroke
				(width 0.1524)
				(type default)
			)
			(layer "B.SilkS")
		)
		(fp_line
			(start 0.7874 -0.4064)
			(end -0.7874 -0.4064)
			(stroke
				(width 0.1524)
				(type default)
			)
			(layer "B.SilkS")
		)
		(fp_line
			(start -0.7874 0.4064)
			(end 0.7874 0.4064)
			(stroke
				(width 0.1524)
				(type default)
			)
			(layer "B.SilkS")
		)
		(fp_line
			(start -0.7874 -0.4064)
			(end -0.7874 0.4064)
			(stroke
				(width 0.1524)
				(type default)
			)
			(layer "B.SilkS")
		)
		(fp_line
			(start 0.67945 0.3048)
			(end 0.67945 -0.305054)
			(stroke
				(width 0.1)
				(type default)
			)
			(layer "B.Fab")
		)
		(fp_line
			(start 0.67945 -0.305054)
			(end 0.12065 -0.305054)
			(stroke
				(width 0.1)
				(type default)
			)
			(layer "B.Fab")
		)
		(fp_line
			(start 0.12065 0.3048)
			(end 0.67945 0.3048)
			(stroke
				(width 0.1)
				(type default)
			)
			(layer "B.Fab")
		)
		(fp_line
			(start 0.12065 0.2794)
			(end 0.12065 0.3048)
			(stroke
				(width 0.1)
				(type default)
			)
			(layer "B.Fab")
		)
		(fp_line
			(start 0.12065 -0.2794)
			(end -0.12065 -0.2794)
			(stroke
				(width 0.1)
				(type default)
			)
			(layer "B.Fab")
		)
		(fp_line
			(start 0.12065 -0.305054)
			(end 0.12065 -0.2794)
			(stroke
				(width 0.1)
				(type default)
			)
			(layer "B.Fab")
		)
		(fp_line
			(start -0.120396 0.3048)
			(end -0.120396 0.2794)
			(stroke
				(width 0.1)
				(type default)
			)
			(layer "B.Fab")
		)
		(fp_line
			(start -0.120396 0.2794)
			(end 0.12065 0.2794)
			(stroke
				(width 0.1)
				(type default)
			)
			(layer "B.Fab")
		)
		(fp_line
			(start -0.12065 -0.2794)
			(end -0.12065 -0.3048)
			(stroke
				(width 0.1)
				(type default)
			)
			(layer "B.Fab")
		)
		(fp_line
			(start -0.12065 -0.3048)
			(end -0.67945 -0.3048)
			(stroke
				(width 0.1)
				(type default)
			)
			(layer "B.Fab")
		)
		(fp_line
			(start -0.67945 0.3048)
			(end -0.120396 0.3048)
			(stroke
				(width 0.1)
				(type default)
			)
			(layer "B.Fab")
		)
		(fp_line
			(start -0.67945 -0.3048)
			(end -0.67945 0.3048)
			(stroke
				(width 0.1)
				(type default)
			)
			(layer "B.Fab")
		)
		(pad "1" smd circle
			(at 0.40005 0)
			(size 0 0)
			(layers "B.Cu" "B.Mask" "B.Paste")
			(net "PVDDCR_SOC_P1")
		)
		(pad "2" smd circle
			(at -0.40005 0)
			(size 0 0)
			(layers "B.Cu" "B.Mask" "B.Paste")
			(net "GND")
		)
	)
	(footprint ""
		(layer "B.Cu")
		(at 354.152454 -251.78131)
		(property "Reference" "C2576"
			(at 0 0 0)
			(layer "B.SilkS")
			(hide yes)
			(effects
				(font
					(size 1.27 1.27)
				)
				(justify mirror)
			)
		)
		(property "Value" ""
			(at 0 0 0)
			(layer "B.Fab")
			(effects
				(font
					(size 1.27 1.27)
				)
				(justify mirror)
			)
		)
		(duplicate_pad_numbers_are_jumpers no)
		(fp_line
			(start -0.7874 -0.4064)
			(end -0.7874 0.4064)
			(stroke
				(width 0.1524)
				(type default)
			)
			(layer "B.SilkS")
		)
		(fp_line
			(start -0.7874 0.4064)
			(end 0.7874 0.4064)
			(stroke
				(width 0.1524)
				(type default)
			)
			(layer "B.SilkS")
		)
		(fp_line
			(start 0.7874 -0.4064)
			(end -0.7874 -0.4064)
			(stroke
				(width 0.1524)
				(type default)
			)
			(layer "B.SilkS")
		)
		(fp_line
			(start 0.7874 0.4064)
			(end 0.7874 -0.4064)
			(stroke
				(width 0.1524)
				(type default)
			)
			(layer "B.SilkS")
		)
		(fp_line
			(start -0.67945 -0.3048)
			(end -0.67945 0.3048)
			(stroke
				(width 0.1)
				(type default)
			)
			(layer "B.Fab")
		)
		(fp_line
			(start -0.67945 0.3048)
			(end -0.120396 0.3048)
			(stroke
				(width 0.1)
				(type default)
			)
			(layer "B.Fab")
		)
		(fp_line
			(start -0.12065 -0.3048)
			(end -0.67945 -0.3048)
			(stroke
				(width 0.1)
				(type default)
			)
			(layer "B.Fab")
		)
		(fp_line
			(start -0.12065 -0.2794)
			(end -0.12065 -0.3048)
			(stroke
				(width 0.1)
				(type default)
			)
			(layer "B.Fab")
		)
		(fp_line
			(start -0.120396 0.2794)
			(end 0.12065 0.2794)
			(stroke
				(width 0.1)
				(type default)
			)
			(layer "B.Fab")
		)
		(fp_line
			(start -0.120396 0.3048)
			(end -0.120396 0.2794)
			(stroke
				(width 0.1)
				(type default)
			)
			(layer "B.Fab")
		)
		(fp_line
			(start 0.12065 -0.305054)
			(end 0.12065 -0.2794)
			(stroke
				(width 0.1)
				(type default)
			)
			(layer "B.Fab")
		)
		(fp_line
			(start 0.12065 -0.2794)
			(end -0.12065 -0.2794)
			(stroke
				(width 0.1)
				(type default)
			)
			(layer "B.Fab")
		)
		(fp_line
			(start 0.12065 0.2794)
			(end 0.12065 0.3048)
			(stroke
				(width 0.1)
				(type default)
			)
			(layer "B.Fab")
		)
		(fp_line
			(start 0.12065 0.3048)
			(end 0.67945 0.3048)
			(stroke
				(width 0.1)
				(type default)
			)
			(layer "B.Fab")
		)
		(fp_line
			(start 0.67945 -0.305054)
			(end 0.12065 -0.305054)
			(stroke
				(width 0.1)
				(type default)
			)
			(layer "B.Fab")
		)
		(fp_line
			(start 0.67945 0.3048)
			(end 0.67945 -0.305054)
			(stroke
				(width 0.1)
				(type default)
			)
			(layer "B.Fab")
		)
		(pad "1" smd circle
			(at 0.40005 0 180)
			(size 0 0)
			(layers "B.Cu" "B.Mask" "B.Paste")
			(net "PVDDCR_SOC_P0")
		)
		(pad "2" smd circle
			(at -0.40005 0 180)
			(size 0 0)
			(layers "B.Cu" "B.Mask" "B.Paste")
			(net "GND")
		)
	)
	(footprint ""
		(layer "B.Cu")
		(at 337.661504 -151.064722 90)
		(property "Reference" "PC288"
			(at 0 0 90)
			(layer "B.SilkS")
			(hide yes)
			(effects
				(font
					(size 1.27 1.27)
				)
				(justify mirror)
			)
		)
		(property "Value" ""
			(at 0 0 90)
			(layer "B.Fab")
			(effects
				(font
					(size 1.27 1.27)
				)
				(justify mirror)
			)
		)
		(duplicate_pad_numbers_are_jumpers no)
		(fp_line
			(start 1.524 -0.762)
			(end -1.524 -0.762)
			(stroke
				(width 0.1524)
				(type default)
			)
			(layer "B.SilkS")
		)
		(fp_line
			(start -1.524 -0.762)
			(end -1.524 0.762)
			(stroke
				(width 0.1524)
				(type default)
			)
			(layer "B.SilkS")
		)
		(fp_line
			(start 1.524 0.762)
			(end 1.524 -0.762)
			(stroke
				(width 0.1524)
				(type default)
			)
			(layer "B.SilkS")
		)
		(fp_line
			(start -1.524 0.762)
			(end 1.524 0.762)
			(stroke
				(width 0.1524)
				(type default)
			)
			(layer "B.SilkS")
		)
		(fp_line
			(start 1.1049 -0.724916)
			(end 1.1049 0.724916)
			(stroke
				(width 0.1)
				(type default)
			)
			(layer "B.Fab")
		)
		(fp_line
			(start -1.1049 -0.724916)
			(end 1.1049 -0.724916)
			(stroke
				(width 0.1)
				(type default)
			)
			(layer "B.Fab")
		)
		(fp_line
			(start 1.1049 0.724916)
			(end -1.1049 0.724916)
			(stroke
				(width 0.1)
				(type default)
			)
			(layer "B.Fab")
		)
		(fp_line
			(start -1.1049 0.724916)
			(end -1.1049 -0.724916)
			(stroke
				(width 0.1)
				(type default)
			)
			(layer "B.Fab")
		)
		(pad "1" smd rect
			(at 0.889 0 90)
			(size 1.016 1.27)
			(layers "B.Cu" "B.Mask" "B.Paste")
			(net "PVDD18_S5_P0")
		)
		(pad "2" smd rect
			(at -0.889 0 90)
			(size 1.016 1.27)
			(layers "B.Cu" "B.Mask" "B.Paste")
			(net "GND")
		)
	)
)
